# T6G (Grand Teton) — schematic netlist excerpt (pin names and nets, part order shuffled) for the footprints in the layout excerpt that follows; sources: Cadence DE-HDL packaged netlist, KiCad conversion of 04192023_DAF0TMB3IC0_F0TG_MB_C_brd_V02_OCP.brd

L33  Q_INDUCTOR  BLM15PD121SN1D/1300MA IND  pkg SMLF  page 356 : \1\ = P1V8_CPU1_RT_1D ; \2\ = P1V8_CPU1_RT3_1A_1D
PC372_C1P1_2  Q_CAP  2.2UF 10V 10% X6S  pkg C0402  page 218 : A = PVDDCR_CPU1_P1_PVCC ; B = GND

(kicad_pcb
	(version 20260206)
	(generator "pcbnew")
	(generator_version "10.0")
	(general
		(thickness 1.6)
		(legacy_teardrops no)
	)
	(paper "A4")
	(title_block
		(title "04192023_DAF0TMB3IC0_F0TG_MB_C_brd_V02_OCP.brd")
		(comment 1 "Grand Teton / footprints 1662-1663 of 8354")
	)
	(layers
		(0 "F.Cu" signal "TOP")
		(4 "In1.Cu" signal "GND")
		(6 "In2.Cu" signal "IN1")
		(8 "In3.Cu" signal "GND1")
		(10 "In4.Cu" signal "IN2")
		(12 "In5.Cu" signal "GND2")
		(14 "In6.Cu" signal "IN3")
		(16 "In7.Cu" signal "GND3")
		(18 "In8.Cu" signal "VCC")
		(20 "In9.Cu" signal "VCC1")
		(22 "In10.Cu" signal "GND4")
		(24 "In11.Cu" signal "IN4")
		(26 "In12.Cu" signal "GND5")
		(28 "In13.Cu" signal "IN5")
		(30 "In14.Cu" signal "GND6")
		(32 "In15.Cu" signal "IN6")
		(34 "In16.Cu" signal "GND7")
		(2 "B.Cu" signal "BOTTOM")
		(9 "F.Adhes" user "F.Adhesive")
		(11 "B.Adhes" user "B.Adhesive")
		(13 "F.Paste" user "Package Geometry/Pastemask Top")
		(15 "B.Paste" user "Package Geometry/Pastemask Bottom")
		(5 "F.SilkS" user "Ref Des/Silkscreen Top")
		(7 "B.SilkS" user "Ref Des/Silkscreen Bottom")
		(1 "F.Mask" user "Board Geometry/Soldermask Top")
		(3 "B.Mask" user "Board Geometry/Soldermask Bottom")
		(17 "Dwgs.User" user "User.Drawings")
		(19 "Cmts.User" user "User.Comments")
		(21 "Eco1.User" user "User.Eco1")
		(23 "Eco2.User" user "User.Eco2")
		(25 "Edge.Cuts" user "Board Geometry/Outline")
		(27 "Margin" user)
		(31 "F.CrtYd" user "Package Geometry/Place Bound Top")
		(29 "B.CrtYd" user "Package Geometry/Place Bound Bottom")
		(35 "F.Fab" user "Ref Des/Assembly Top")
		(33 "B.Fab" user "Ref Des/Assembly Bottom")
	)
	(footprint ""
		(layer "F.Cu")
		(at 137.762488 -385.09448 180)
		(property "Reference" "L33"
			(at 0 0 180)
			(layer "F.SilkS")
			(hide yes)
			(effects
				(font
					(size 1.27 1.27)
				)
			)
		)
		(property "Value" ""
			(at 0 0 180)
			(layer "F.Fab")
			(effects
				(font
					(size 1.27 1.27)
				)
			)
		)
		(duplicate_pad_numbers_are_jumpers no)
		(fp_line
			(start 0.762 0.381)
			(end -0.762 0.381)
			(stroke
				(width 0.1524)
				(type default)
			)
			(layer "F.SilkS")
		)
		(fp_line
			(start 0.762 -0.381)
			(end 0.762 0.381)
			(stroke
				(width 0.1524)
				(type default)
			)
			(layer "F.SilkS")
		)
		(fp_line
			(start -0.762 0.381)
			(end -0.762 -0.381)
			(stroke
				(width 0.1524)
				(type default)
			)
			(layer "F.SilkS")
		)
		(fp_line
			(start -0.762 -0.381)
			(end 0.762 -0.381)
			(stroke
				(width 0.1524)
				(type default)
			)
			(layer "F.SilkS")
		)
		(fp_line
			(start 0.680466 0.306324)
			(end 0.118364 0.306324)
			(stroke
				(width 0.1)
				(type default)
			)
			(layer "F.Fab")
		)
		(fp_line
			(start 0.680466 -0.306324)
			(end 0.680466 0.306324)
			(stroke
				(width 0.1)
				(type default)
			)
			(layer "F.Fab")
		)
		(fp_line
			(start 0.118872 -0.2794)
			(end 0.118872 -0.306324)
			(stroke
				(width 0.1)
				(type default)
			)
			(layer "F.Fab")
		)
		(fp_line
			(start 0.118872 -0.306324)
			(end 0.680466 -0.306324)
			(stroke
				(width 0.1)
				(type default)
			)
			(layer "F.Fab")
		)
		(fp_line
			(start 0.118364 0.306324)
			(end 0.118364 0.2794)
			(stroke
				(width 0.1)
				(type default)
			)
			(layer "F.Fab")
		)
		(fp_line
			(start 0.118364 0.2794)
			(end -0.119634 0.2794)
			(stroke
				(width 0.1)
				(type default)
			)
			(layer "F.Fab")
		)
		(fp_line
			(start -0.118364 -0.2794)
			(end 0.118872 -0.2794)
			(stroke
				(width 0.1)
				(type default)
			)
			(layer "F.Fab")
		)
		(fp_line
			(start -0.118364 -0.307086)
			(end -0.118364 -0.2794)
			(stroke
				(width 0.1)
				(type default)
			)
			(layer "F.Fab")
		)
		(fp_line
			(start -0.119634 0.30607)
			(end -0.681736 0.30607)
			(stroke
				(width 0.1)
				(type default)
			)
			(layer "F.Fab")
		)
		(fp_line
			(start -0.119634 0.2794)
			(end -0.119634 0.30607)
			(stroke
				(width 0.1)
				(type default)
			)
			(layer "F.Fab")
		)
		(fp_line
			(start -0.681736 0.30607)
			(end -0.681736 -0.307086)
			(stroke
				(width 0.1)
				(type default)
			)
			(layer "F.Fab")
		)
		(fp_line
			(start -0.681736 -0.307086)
			(end -0.118364 -0.307086)
			(stroke
				(width 0.1)
				(type default)
			)
			(layer "F.Fab")
		)
		(pad "1" smd rect
			(at -0.40005 0)
			(size 0.4572 0.508)
			(layers "F.Cu" "F.Mask" "F.Paste")
			(net "P1V8_CPU1_RT_1D")
		)
		(pad "2" smd rect
			(at 0.40005 0)
			(size 0.4572 0.508)
			(layers "F.Cu" "F.Mask" "F.Paste")
			(net "P1V8_CPU1_RT3_1A_1D")
		)
	)
	(footprint ""
		(layer "F.Cu")
		(at 75.081638 -334.991202 -90)
		(property "Reference" "PC372_C1P1_2"
			(at 0 0 270)
			(layer "F.SilkS")
			(hide yes)
			(effects
				(font
					(size 1.27 1.27)
				)
			)
		)
		(property "Value" ""
			(at 0 0 270)
			(layer "F.Fab")
			(effects
				(font
					(size 1.27 1.27)
				)
			)
		)
		(duplicate_pad_numbers_are_jumpers no)
		(fp_line
			(start -0.7874 0.4064)
			(end -0.7874 -0.4064)
			(stroke
				(width 0.1524)
				(type default)
			)
			(layer "F.SilkS")
		)
		(fp_line
			(start 0.7874 0.4064)
			(end -0.7874 0.4064)
			(stroke
				(width 0.1524)
				(type default)
			)
			(layer "F.SilkS")
		)
		(fp_line
			(start -0.7874 -0.4064)
			(end 0.7874 -0.4064)
			(stroke
				(width 0.1524)
				(type default)
			)
			(layer "F.SilkS")
		)
		(fp_line
			(start 0.7874 -0.4064)
			(end 0.7874 0.4064)
			(stroke
				(width 0.1524)
				(type default)
			)
			(layer "F.SilkS")
		)
		(fp_line
			(start -0.67945 0.3048)
			(end -0.67945 -0.305054)
			(stroke
				(width 0.1)
				(type default)
			)
			(layer "F.Fab")
		)
		(fp_line
			(start -0.12065 0.3048)
			(end -0.67945 0.3048)
			(stroke
				(width 0.1)
				(type default)
			)
			(layer "F.Fab")
		)
		(fp_line
			(start 0.120396 0.3048)
			(end 0.120396 0.2794)
			(stroke
				(width 0.1)
				(type default)
			)
			(layer "F.Fab")
		)
		(fp_line
			(start 0.67945 0.3048)
			(end 0.120396 0.3048)
			(stroke
				(width 0.1)
				(type default)
			)
			(layer "F.Fab")
		)
		(fp_line
			(start -0.12065 0.2794)
			(end -0.12065 0.3048)
			(stroke
				(width 0.1)
				(type default)
			)
			(layer "F.Fab")
		)
		(fp_line
			(start 0.120396 0.2794)
			(end -0.12065 0.2794)
			(stroke
				(width 0.1)
				(type default)
			)
			(layer "F.Fab")
		)
		(fp_line
			(start -0.12065 -0.2794)
			(end 0.12065 -0.2794)
			(stroke
				(width 0.1)
				(type default)
			)
			(layer "F.Fab")
		)
		(fp_line
			(start 0.12065 -0.2794)
			(end 0.12065 -0.3048)
			(stroke
				(width 0.1)
				(type default)
			)
			(layer "F.Fab")
		)
		(fp_line
			(start 0.12065 -0.3048)
			(end 0.67945 -0.3048)
			(stroke
				(width 0.1)
				(type default)
			)
			(layer "F.Fab")
		)
		(fp_line
			(start 0.67945 -0.3048)
			(end 0.67945 0.3048)
			(stroke
				(width 0.1)
				(type default)
			)
			(layer "F.Fab")
		)
		(fp_line
			(start -0.67945 -0.305054)
			(end -0.12065 -0.305054)
			(stroke
				(width 0.1)
				(type default)
			)
			(layer "F.Fab")
		)
		(fp_line
			(start -0.12065 -0.305054)
			(end -0.12065 -0.2794)
			(stroke
				(width 0.1)
				(type default)
			)
			(layer "F.Fab")
		)
		(pad "1" smd circle
			(at -0.40005 0 270)
			(size 0 0)
			(layers "F.Cu" "F.Mask" "F.Paste")
			(net "PVDDCR_CPU1_P1_PVCC")
		)
		(pad "2" smd circle
			(at 0.40005 0 270)
			(size 0 0)
			(layers "F.Cu" "F.Mask" "F.Paste")
			(net "GND")
		)
	)
)
